(kicad_pcb
	(version 20260206)
	(generator "pcbnew")
	(generator_version "10.0")
	(general
		(thickness 1.6)
		(legacy_teardrops no)
	)
	(paper "A4")
	(title_block
		(title "timecard-production-celestica-r4006 — R4006-B0001-02_R01.brd")
		(comment 1 "Time Appliance Project (Time Card) / footprints 145-149 of 1113")
	)
	(layers
		(0 "F.Cu" signal "TOP")
		(4 "In1.Cu" signal "L02_GND1")
		(6 "In2.Cu" signal "L03_SIG1")
		(8 "In3.Cu" signal "L04_GND2")
		(10 "In4.Cu" signal "L05_VCC1")
		(12 "In5.Cu" signal "L06_VCC2")
		(14 "In6.Cu" signal "L07_GND3")
		(16 "In7.Cu" signal "L08_SIG2")
		(18 "In8.Cu" signal "L09_GND4")
		(2 "B.Cu" signal "BOTTOM")
		(9 "F.Adhes" user "F.Adhesive")
		(11 "B.Adhes" user "B.Adhesive")
		(13 "F.Paste" user "Package Geometry/Pastemask Top")
		(15 "B.Paste" user "Package Geometry/Pastemask Bottom")
		(5 "F.SilkS" user "Ref Des/Silkscreen Top")
		(7 "B.SilkS" user "Ref Des/Silkscreen Bottom")
		(1 "F.Mask" user "Board Geometry/Soldermask Top")
		(3 "B.Mask" user "Board Geometry/Soldermask Bottom")
		(17 "Dwgs.User" user "User.Drawings")
		(19 "Cmts.User" user "User.Comments")
		(21 "Eco1.User" user "User.Eco1")
		(23 "Eco2.User" user "User.Eco2")
		(25 "Edge.Cuts" user "Board Geometry/Outline")
		(27 "Margin" user)
		(31 "F.CrtYd" user "Package Geometry/Place Bound Top")
		(29 "B.CrtYd" user "Package Geometry/Place Bound Bottom")
		(35 "F.Fab" user "Ref Des/Assembly Top")
		(33 "B.Fab" user "Ref Des/Assembly Bottom")
	)
	(footprint ""
		(layer "F.Cu")
		(at 1.500124 -53.600096 90)
		(property "Reference" "DS17"
			(at 2.875534 0.785876 0)
			(unlocked yes)
			(layer "F.SilkS")
			(effects
				(font
					(size 0.7874 0.5842)
					(thickness 0.1524)
				)
			)
		)
		(property "Value" ""
			(at 0 0 90)
			(layer "F.Fab")
			(effects
				(font
					(size 1.27 1.27)
				)
			)
		)
		(property "User Part Number" "PARTNUM*"
			(at 0.015494 4.486402 90)
			(unlocked yes)
			(layer "Cmts.User")
			(hide yes)
			(effects
				(font
					(size 0.7874 0.5842)
					(thickness 0.1524)
				)
			)
		)
		(property "Device Type" "LED_4P_V14-G170-10189-01"
			(at 0.015494 3.292602 90)
			(unlocked yes)
			(layer "F.Fab")
			(hide yes)
			(effects
				(font
					(size 0.7874 0.5842)
					(thickness 0.1524)
				)
			)
		)
		(duplicate_pad_numbers_are_jumpers no)
		(fp_line
			(start 1.378966 -0.829056)
			(end -1.378966 -0.829056)
			(stroke
				(width 0.1)
				(type default)
			)
			(layer "F.SilkS")
		)
		(fp_line
			(start -1.378966 -0.829056)
			(end -1.378966 -0.452628)
			(stroke
				(width 0.1)
				(type default)
			)
			(layer "F.SilkS")
		)
		(fp_line
			(start 1.998218 -0.452628)
			(end 1.378966 -0.452628)
			(stroke
				(width 0.1)
				(type default)
			)
			(layer "F.SilkS")
		)
		(fp_line
			(start 1.378966 -0.452628)
			(end 1.378966 -0.829056)
			(stroke
				(width 0.1)
				(type default)
			)
			(layer "F.SilkS")
		)
		(fp_line
			(start -1.378966 -0.452628)
			(end -1.998218 -0.452628)
			(stroke
				(width 0.1)
				(type default)
			)
			(layer "F.SilkS")
		)
		(fp_line
			(start -1.998218 -0.452628)
			(end -1.998218 1.103884)
			(stroke
				(width 0.1)
				(type default)
			)
			(layer "F.SilkS")
		)
		(fp_line
			(start 1.998218 1.103884)
			(end 1.998218 -0.452628)
			(stroke
				(width 0.1)
				(type default)
			)
			(layer "F.SilkS")
		)
		(fp_line
			(start -1.998218 1.103884)
			(end 1.998218 1.103884)
			(stroke
				(width 0.1)
				(type default)
			)
			(layer "F.SilkS")
		)
		(fp_poly
			(pts
				(xy 0.918464 -1.698498) (xy 1.223264 -1.46939) (xy 0.994664 -1.46939) (xy 0.994664 -1.24079) (xy 0.842264 -1.24079)
				(xy 0.842264 -1.46939) (xy 0.613664 -1.46939)
			)
			(stroke
				(width 0)
				(type default)
			)
			(fill yes)
			(layer "F.SilkS")
		)
		(fp_poly
			(pts
				(xy -0.73406 -1.677416) (xy -0.42926 -1.448308) (xy -0.65786 -1.448308) (xy -0.65786 -1.219708)
				(xy -0.81026 -1.219708) (xy -0.81026 -1.448308) (xy -1.03886 -1.448308)
			)
			(stroke
				(width 0)
				(type default)
			)
			(fill yes)
			(layer "F.SilkS")
		)
		(fp_poly
			(pts
				(xy -2.252218 1.357884) (xy -2.252218 -0.706628) (xy -1.632966 -0.706628) (xy -1.632966 -1.083056)
				(xy 1.632966 -1.083056) (xy 1.632966 -0.706628) (xy 2.252218 -0.706628) (xy 2.252218 1.357884)
			)
			(stroke
				(width 0)
				(type default)
			)
			(fill no)
			(layer "F.CrtYd")
		)
		(fp_line
			(start 1.124966 -0.575056)
			(end -1.124966 -0.575056)
			(stroke
				(width 0.1)
				(type default)
			)
			(layer "F.Fab")
		)
		(fp_line
			(start -1.124966 -0.575056)
			(end -1.124966 -0.075184)
			(stroke
				(width 0.1)
				(type default)
			)
			(layer "F.Fab")
		)
		(fp_line
			(start 1.325118 -0.075184)
			(end 1.124966 -0.075184)
			(stroke
				(width 0.1)
				(type default)
			)
			(layer "F.Fab")
		)
		(fp_line
			(start 1.124966 -0.075184)
			(end 1.124966 -0.575056)
			(stroke
				(width 0.1)
				(type default)
			)
			(layer "F.Fab")
		)
		(fp_line
			(start -1.124966 -0.075184)
			(end -1.325118 -0.075184)
			(stroke
				(width 0.1)
				(type default)
			)
			(layer "F.Fab")
		)
		(fp_line
			(start -1.325118 -0.075184)
			(end -1.325118 0.574802)
			(stroke
				(width 0.1)
				(type default)
			)
			(layer "F.Fab")
		)
		(fp_line
			(start 1.325118 0.574802)
			(end 1.325118 -0.075184)
			(stroke
				(width 0.1)
				(type default)
			)
			(layer "F.Fab")
		)
		(fp_line
			(start -1.325118 0.574802)
			(end 1.325118 0.574802)
			(stroke
				(width 0.1)
				(type default)
			)
			(layer "F.Fab")
		)
		(fp_poly
			(pts
				(xy 0.918464 -1.698498) (xy 1.223264 -1.46939) (xy 0.994664 -1.46939) (xy 0.994664 -1.24079) (xy 0.842264 -1.24079)
				(xy 0.842264 -1.46939) (xy 0.613664 -1.46939)
			)
			(stroke
				(width 0)
				(type default)
			)
			(fill yes)
			(layer "F.Fab")
		)
		(fp_poly
			(pts
				(xy -0.73406 -1.677416) (xy -0.42926 -1.448308) (xy -0.65786 -1.448308) (xy -0.65786 -1.219708)
				(xy -0.81026 -1.219708) (xy -0.81026 -1.448308) (xy -1.03886 -1.448308)
			)
			(stroke
				(width 0)
				(type default)
			)
			(fill yes)
			(layer "F.Fab")
		)
		(fp_text user "1"
			(at -2.37617 0.376936 90)
			(unlocked yes)
			(layer "F.SilkS")
			(effects
				(font
					(size 0.7874 0.5842)
					(thickness 0.1524)
				)
			)
		)
		(fp_text user "2"
			(at -1.053846 1.420876 0)
			(unlocked yes)
			(layer "F.SilkS")
			(effects
				(font
					(size 0.635 0.4064)
					(thickness 0.1524)
				)
			)
		)
		(fp_text user "3"
			(at 1.486154 1.547876 0)
			(unlocked yes)
			(layer "F.SilkS")
			(effects
				(font
					(size 0.635 0.4064)
					(thickness 0.1524)
				)
			)
		)
		(fp_text user "4"
			(at 2.03835 1.166876 0)
			(unlocked yes)
			(layer "F.Fab")
			(effects
				(font
					(size 0.7874 0.5842)
					(thickness 0.1524)
				)
			)
		)
		(fp_text user "3"
			(at 1.02235 1.166876 0)
			(unlocked yes)
			(layer "F.Fab")
			(effects
				(font
					(size 0.7874 0.5842)
					(thickness 0.1524)
				)
			)
		)
		(fp_text user "2"
			(at 0.00635 1.166876 0)
			(unlocked yes)
			(layer "F.Fab")
			(effects
				(font
					(size 0.7874 0.5842)
					(thickness 0.1524)
				)
			)
		)
		(fp_text user "1"
			(at -1.061466 1.166876 0)
			(unlocked yes)
			(layer "F.Fab")
			(effects
				(font
					(size 0.7874 0.5842)
					(thickness 0.1524)
				)
			)
		)
		(pad "1" smd rect
			(at -1.325118 0.245872 90)
			(size 0.8382 0.889)
			(layers "F.Cu" "F.Mask" "F.Paste")
			(net "UNNAMED_14_LED4PV14_I268_1")
		)
		(pad "2" smd rect
			(at -0.424942 0.595884 90)
			(size 0.4572 0.508)
			(layers "F.Cu" "F.Mask" "F.Paste")
			(net "XP3R3V_FPGA")
		)
		(pad "3" smd rect
			(at 0.424942 0.595884 90)
			(size 0.4572 0.508)
			(layers "F.Cu" "F.Mask" "F.Paste")
			(net "UNNAMED_14_LED4PV14_I268_3")
		)
		(pad "4" smd rect
			(at 1.325118 0.245872 90)
			(size 0.8382 0.889)
			(layers "F.Cu" "F.Mask" "F.Paste")
			(net "UNNAMED_14_LED4PV14_I268_4")
		)
	)
	(footprint ""
		(layer "F.Cu")
		(at 107.188 -31.369 90)
		(property "Reference" "TP200"
			(at -3.0988 0.15875 90)
			(unlocked yes)
			(layer "F.SilkS")
			(effects
				(font
					(size 0.635 0.4064)
					(thickness 0.1524)
				)
				(justify left)
			)
		)
		(property "Value" ""
			(at 0 0 90)
			(layer "F.Fab")
			(effects
				(font
					(size 1.27 1.27)
				)
			)
		)
		(property "Device Type" "TP_PIONT-TP010CT020B030_PTH-TPA"
			(at -1.341882 0.996696 90)
			(unlocked yes)
			(layer "F.Fab")
			(hide yes)
			(effects
				(font
					(size 0.7874 0.5842)
					(thickness 0.1524)
				)
				(justify left)
			)
		)
		(duplicate_pad_numbers_are_jumpers no)
		(fp_poly
			(pts
				(arc
					(start 0 0.889)
					(mid 0 -0.889)
					(end 0 0.889)
				)
			)
			(stroke
				(width 0)
				(type default)
			)
			(fill no)
			(layer "B.CrtYd")
		)
		(fp_poly
			(pts
				(arc
					(start 0 0.889)
					(mid 0 -0.889)
					(end 0 0.889)
				)
			)
			(stroke
				(width 0)
				(type default)
			)
			(fill no)
			(layer "F.CrtYd")
		)
		(pad "1" thru_hole circle
			(at 0 0 90)
			(size 0.508 0.508)
			(drill 0.254)
			(layers "*.Cu" "*.Mask")
			(remove_unused_layers no)
			(net "IO_L20N_35")
			(clearance 0.1016)
			(padstack
				(mode front_inner_back)
				(layer "Inner"
					(shape circle)
					(size 0.508 0.508)
					(clearance 0.1016)
				)
				(layer "B.Cu"
					(shape circle)
					(size 0.762 0.762)
					(clearance -0.0254)
				)
			)
		)
	)
	(footprint ""
		(layer "F.Cu")
		(at 43.4594 -95.9104)
		(property "Reference" "C32"
			(at 0.127 4.05257 0)
			(unlocked yes)
			(layer "F.SilkS")
			(effects
				(font
					(size 0.7874 0.5842)
					(thickness 0.1524)
				)
			)
		)
		(property "Value" "VAL*"
			(at 0.0762 3.134106 0)
			(unlocked yes)
			(layer "F.Fab")
			(hide yes)
			(effects
				(font
					(size 0.7874 0.5842)
					(thickness 0.1524)
				)
			)
		)
		(property "Device Type" "CAPACITOR-G107-0F106-EM,10UF,2A"
			(at 0.0508 2.194306 0)
			(unlocked yes)
			(layer "F.Fab")
			(hide yes)
			(effects
				(font
					(size 0.7874 0.5842)
					(thickness 0.1524)
				)
			)
		)
		(property "User Part Number" "PARTNUM*"
			(at 0.1016 5.013706 0)
			(unlocked yes)
			(layer "Cmts.User")
			(hide yes)
			(effects
				(font
					(size 0.7874 0.5842)
					(thickness 0.1524)
				)
			)
		)
		(property "Tolerance" "TOL*"
			(at 0.0762 4.048506 0)
			(unlocked yes)
			(layer "Cmts.User")
			(hide yes)
			(effects
				(font
					(size 0.7874 0.5842)
					(thickness 0.1524)
				)
			)
		)
		(duplicate_pad_numbers_are_jumpers no)
		(fp_line
			(start -1.5748 -0.9398)
			(end -1.5748 0.9398)
			(stroke
				(width 0.1)
				(type default)
			)
			(layer "F.SilkS")
		)
		(fp_line
			(start -1.5748 0.9398)
			(end 1.5748 0.9398)
			(stroke
				(width 0.1)
				(type default)
			)
			(layer "F.SilkS")
		)
		(fp_line
			(start 1.5748 -0.9398)
			(end -1.5748 -0.9398)
			(stroke
				(width 0.1)
				(type default)
			)
			(layer "F.SilkS")
		)
		(fp_line
			(start 1.5748 0.9398)
			(end 1.5748 -0.9398)
			(stroke
				(width 0.1)
				(type default)
			)
			(layer "F.SilkS")
		)
		(fp_rect
			(start 1.5748 -0.9398)
			(end -1.5748 0.9398)
			(stroke
				(width 0)
				(type default)
			)
			(fill no)
			(layer "F.CrtYd")
		)
		(fp_line
			(start -1.016 -0.635)
			(end -1.016 0.635)
			(stroke
				(width 0.1)
				(type default)
			)
			(layer "F.Fab")
		)
		(fp_line
			(start -1.016 0.635)
			(end 1.016 0.635)
			(stroke
				(width 0.1)
				(type default)
			)
			(layer "F.Fab")
		)
		(fp_line
			(start 1.016 -0.635)
			(end -1.016 -0.635)
			(stroke
				(width 0.1)
				(type default)
			)
			(layer "F.Fab")
		)
		(fp_line
			(start 1.016 0.635)
			(end 1.016 -0.635)
			(stroke
				(width 0.1)
				(type default)
			)
			(layer "F.Fab")
		)
		(pad "1" smd rect
			(at -0.8382 0)
			(size 0.9652 1.3716)
			(layers "F.Cu" "F.Mask" "F.Paste")
			(net "VIN_XP5R0V")
		)
		(pad "2" smd rect
			(at 0.8382 0)
			(size 0.9652 1.3716)
			(layers "F.Cu" "F.Mask" "F.Paste")
			(net "SG")
		)
		(zone
			(layer "F.Cu")
			(hatch none 0.5)
			(connect_pads
				(clearance 0)
			)
			(min_thickness 0.25)
			(keepout
				(tracks allowed)
				(vias not_allowed)
				(pads allowed)
				(copperpour not_allowed)
				(footprints allowed)
			)
			(placement
				(enabled no)
				(sheetname "")
			)
			(fill
				(thermal_gap 0.5)
				(thermal_bridge_width 0.5)
				(island_removal_mode 0)
			)
			(polygon
				(pts
					(xy 43.688 -96.5454) (xy 43.2308 -96.5454) (xy 43.2308 -95.2754) (xy 43.688 -95.2754)
				)
			)
		)
	)
	(footprint ""
		(layer "F.Cu")
		(at 51.054 -126.111)
		(property "Reference" "SP69"
			(at 0 0 0)
			(layer "F.SilkS")
			(hide yes)
			(effects
				(font
					(size 1.27 1.27)
				)
			)
		)
		(property "Value" ""
			(at 0 0 0)
			(layer "F.Fab")
			(effects
				(font
					(size 1.27 1.27)
				)
			)
		)
		(duplicate_pad_numbers_are_jumpers no)
	)
	(footprint ""
		(layer "F.Cu")
		(at 81.0006 -52.324 180)
		(property "Reference" "R84"
			(at 0.9906 -14.39037 0)
			(unlocked yes)
			(layer "F.SilkS")
			(effects
				(font
					(size 0.7874 0.5842)
					(thickness 0.1524)
				)
			)
		)
		(property "Value" "VAL*"
			(at 0.02032 2.13233 180)
			(unlocked yes)
			(layer "F.Fab")
			(hide yes)
			(effects
				(font
					(size 0.7874 0.5842)
					(thickness 0.1524)
				)
			)
		)
		(property "Tolerance" "TOL*"
			(at 0.044704 3.05435 180)
			(unlocked yes)
			(layer "Cmts.User")
			(hide yes)
			(effects
				(font
					(size 0.7874 0.5842)
					(thickness 0.1524)
				)
			)
		)
		(property "User Part Number" "PARTNUM*"
			(at 0.02032 4.024884 180)
			(unlocked yes)
			(layer "Cmts.User")
			(hide yes)
			(effects
				(font
					(size 0.7874 0.5842)
					(thickness 0.1524)
				)
			)
		)
		(property "Device Type" "RESISTOR-G155-100R0-J0,0OHM,-"
			(at 0.008382 1.210564 180)
			(unlocked yes)
			(layer "F.Fab")
			(hide yes)
			(effects
				(font
					(size 0.7874 0.5842)
					(thickness 0.1524)
				)
			)
		)
		(duplicate_pad_numbers_are_jumpers no)
		(fp_line
			(start 1.143 0.5588)
			(end 1.143 -0.5588)
			(stroke
				(width 0.1)
				(type default)
			)
			(layer "F.SilkS")
		)
		(fp_line
			(start 1.143 -0.5588)
			(end -1.143 -0.5588)
			(stroke
				(width 0.1)
				(type default)
			)
			(layer "F.SilkS")
		)
		(fp_line
			(start -1.143 0.5588)
			(end 1.143 0.5588)
			(stroke
				(width 0.1)
				(type default)
			)
			(layer "F.SilkS")
		)
		(fp_line
			(start -1.143 -0.5588)
			(end -1.143 0.5588)
			(stroke
				(width 0.1)
				(type default)
			)
			(layer "F.SilkS")
		)
		(fp_rect
			(start 1.143 -0.5588)
			(end -1.143 0.5588)
			(stroke
				(width 0)
				(type default)
			)
			(fill no)
			(layer "F.CrtYd")
		)
		(fp_line
			(start 0.508 0.3048)
			(end 0.508 -0.3048)
			(stroke
				(width 0.1)
				(type default)
			)
			(layer "F.Fab")
		)
		(fp_line
			(start 0.508 -0.3048)
			(end -0.508 -0.3048)
			(stroke
				(width 0.1)
				(type default)
			)
			(layer "F.Fab")
		)
		(fp_line
			(start -0.508 0.3048)
			(end 0.508 0.3048)
			(stroke
				(width 0.1)
				(type default)
			)
			(layer "F.Fab")
		)
		(fp_line
			(start -0.508 -0.3048)
			(end -0.508 0.3048)
			(stroke
				(width 0.1)
				(type default)
			)
			(layer "F.Fab")
		)
		(pad "1" smd rect
			(at -0.5334 0 180)
			(size 0.7112 0.6096)
			(layers "F.Cu" "F.Mask" "F.Paste")
			(net "FPGA_OUT_MAC_PPS_IN1N")
		)
		(pad "2" smd rect
			(at 0.5334 0 180)
			(size 0.7112 0.6096)
			(layers "F.Cu" "F.Mask" "F.Paste")
			(net "R_MAC_PPS_IN1N")
		)
		(zone
			(layer "F.Cu")
			(hatch none 0.5)
			(connect_pads
				(clearance 0)
			)
			(min_thickness 0.25)
			(keepout
				(tracks allowed)
				(vias not_allowed)
				(pads allowed)
				(copperpour not_allowed)
				(footprints allowed)
			)
			(placement
				(enabled no)
				(sheetname "")
			)
			(fill
				(thermal_gap 0.5)
				(thermal_bridge_width 0.5)
				(island_removal_mode 0)
			)
			(polygon
				(pts
					(xy 80.9244 -52.0192) (xy 81.0768 -52.0192) (xy 81.0768 -52.6288) (xy 80.9244 -52.6288)
				)
			)
		)
	)
)
